# T6G (Grand Teton) — schematic netlist excerpt (pin names and nets, part order shuffled) for the footprints in the layout excerpt that follows; sources: Cadence DE-HDL packaged netlist, KiCad conversion of 04192023_DAF0TMB3IC0_F0TG_MB_C_brd_V02_OCP.brd

PR406  Q_RES  0 5% CHIP  pkg 0402LF  page 224 : A = NC_PVDD11_S3_P1_IMON3 ; B = GND
R6330  Q_RES  4.7K 1% CHIP  pkg 0402LF  page 178 : A = GND ; B = USB_HUB2_TI_NC_MRP_ATEST

(kicad_pcb
	(version 20260206)
	(generator "pcbnew")
	(generator_version "10.0")
	(general
		(thickness 1.6)
		(legacy_teardrops no)
	)
	(paper "A4")
	(title_block
		(title "04192023_DAF0TMB3IC0_F0TG_MB_C_brd_V02_OCP.brd")
		(comment 1 "Grand Teton / footprints 2061-2062 of 8354")
	)
	(layers
		(0 "F.Cu" signal "TOP")
		(4 "In1.Cu" signal "GND")
		(6 "In2.Cu" signal "IN1")
		(8 "In3.Cu" signal "GND1")
		(10 "In4.Cu" signal "IN2")
		(12 "In5.Cu" signal "GND2")
		(14 "In6.Cu" signal "IN3")
		(16 "In7.Cu" signal "GND3")
		(18 "In8.Cu" signal "VCC")
		(20 "In9.Cu" signal "VCC1")
		(22 "In10.Cu" signal "GND4")
		(24 "In11.Cu" signal "IN4")
		(26 "In12.Cu" signal "GND5")
		(28 "In13.Cu" signal "IN5")
		(30 "In14.Cu" signal "GND6")
		(32 "In15.Cu" signal "IN6")
		(34 "In16.Cu" signal "GND7")
		(2 "B.Cu" signal "BOTTOM")
		(9 "F.Adhes" user "F.Adhesive")
		(11 "B.Adhes" user "B.Adhesive")
		(13 "F.Paste" user "Package Geometry/Pastemask Top")
		(15 "B.Paste" user "Package Geometry/Pastemask Bottom")
		(5 "F.SilkS" user "Ref Des/Silkscreen Top")
		(7 "B.SilkS" user "Ref Des/Silkscreen Bottom")
		(1 "F.Mask" user "Board Geometry/Soldermask Top")
		(3 "B.Mask" user "Board Geometry/Soldermask Bottom")
		(17 "Dwgs.User" user "User.Drawings")
		(19 "Cmts.User" user "User.Comments")
		(21 "Eco1.User" user "User.Eco1")
		(23 "Eco2.User" user "User.Eco2")
		(25 "Edge.Cuts" user "Board Geometry/Outline")
		(27 "Margin" user)
		(31 "F.CrtYd" user "Package Geometry/Place Bound Top")
		(29 "B.CrtYd" user "Package Geometry/Place Bound Bottom")
		(35 "F.Fab" user "Ref Des/Assembly Top")
		(33 "B.Fab" user "Ref Des/Assembly Bottom")
	)
	(footprint ""
		(layer "F.Cu")
		(at 162.162744 -344.153998 -90)
		(property "Reference" "PR406"
			(at 0 0 270)
			(layer "F.SilkS")
			(hide yes)
			(effects
				(font
					(size 1.27 1.27)
				)
			)
		)
		(property "Value" ""
			(at 0 0 270)
			(layer "F.Fab")
			(effects
				(font
					(size 1.27 1.27)
				)
			)
		)
		(duplicate_pad_numbers_are_jumpers no)
		(fp_line
			(start -0.7874 0.4064)
			(end -0.7874 -0.4064)
			(stroke
				(width 0.1524)
				(type default)
			)
			(layer "F.SilkS")
		)
		(fp_line
			(start 0.7874 0.4064)
			(end -0.7874 0.4064)
			(stroke
				(width 0.1524)
				(type default)
			)
			(layer "F.SilkS")
		)
		(fp_line
			(start -0.7874 -0.4064)
			(end 0.7874 -0.4064)
			(stroke
				(width 0.1524)
				(type default)
			)
			(layer "F.SilkS")
		)
		(fp_line
			(start 0.7874 -0.4064)
			(end 0.7874 0.4064)
			(stroke
				(width 0.1524)
				(type default)
			)
			(layer "F.SilkS")
		)
		(fp_line
			(start -0.67945 0.3048)
			(end -0.67945 -0.305054)
			(stroke
				(width 0.1)
				(type default)
			)
			(layer "F.Fab")
		)
		(fp_line
			(start -0.12065 0.3048)
			(end -0.67945 0.3048)
			(stroke
				(width 0.1)
				(type default)
			)
			(layer "F.Fab")
		)
		(fp_line
			(start 0.120396 0.3048)
			(end 0.120396 0.2794)
			(stroke
				(width 0.1)
				(type default)
			)
			(layer "F.Fab")
		)
		(fp_line
			(start 0.67945 0.3048)
			(end 0.120396 0.3048)
			(stroke
				(width 0.1)
				(type default)
			)
			(layer "F.Fab")
		)
		(fp_line
			(start -0.12065 0.2794)
			(end -0.12065 0.3048)
			(stroke
				(width 0.1)
				(type default)
			)
			(layer "F.Fab")
		)
		(fp_line
			(start 0.120396 0.2794)
			(end -0.12065 0.2794)
			(stroke
				(width 0.1)
				(type default)
			)
			(layer "F.Fab")
		)
		(fp_line
			(start -0.12065 -0.2794)
			(end 0.12065 -0.2794)
			(stroke
				(width 0.1)
				(type default)
			)
			(layer "F.Fab")
		)
		(fp_line
			(start 0.12065 -0.2794)
			(end 0.12065 -0.3048)
			(stroke
				(width 0.1)
				(type default)
			)
			(layer "F.Fab")
		)
		(fp_line
			(start 0.12065 -0.3048)
			(end 0.67945 -0.3048)
			(stroke
				(width 0.1)
				(type default)
			)
			(layer "F.Fab")
		)
		(fp_line
			(start 0.67945 -0.3048)
			(end 0.67945 0.3048)
			(stroke
				(width 0.1)
				(type default)
			)
			(layer "F.Fab")
		)
		(fp_line
			(start -0.67945 -0.305054)
			(end -0.12065 -0.305054)
			(stroke
				(width 0.1)
				(type default)
			)
			(layer "F.Fab")
		)
		(fp_line
			(start -0.12065 -0.305054)
			(end -0.12065 -0.2794)
			(stroke
				(width 0.1)
				(type default)
			)
			(layer "F.Fab")
		)
		(pad "1" smd circle
			(at -0.40005 0 270)
			(size 0 0)
			(layers "F.Cu" "F.Mask" "F.Paste")
			(net "NC_PVDD11_S3_P1_IMON3")
		)
		(pad "2" smd circle
			(at 0.40005 0 270)
			(size 0 0)
			(layers "F.Cu" "F.Mask" "F.Paste")
			(net "GND")
		)
	)
	(footprint ""
		(layer "F.Cu")
		(at 103.185722 -26.435304 90)
		(property "Reference" "R6330"
			(at 0 0 90)
			(layer "F.SilkS")
			(hide yes)
			(effects
				(font
					(size 1.27 1.27)
				)
			)
		)
		(property "Value" ""
			(at 0 0 90)
			(layer "F.Fab")
			(effects
				(font
					(size 1.27 1.27)
				)
			)
		)
		(duplicate_pad_numbers_are_jumpers no)
		(fp_line
			(start 0.7874 -0.4064)
			(end 0.7874 0.4064)
			(stroke
				(width 0.1524)
				(type default)
			)
			(layer "F.SilkS")
		)
		(fp_line
			(start -0.7874 -0.4064)
			(end 0.7874 -0.4064)
			(stroke
				(width 0.1524)
				(type default)
			)
			(layer "F.SilkS")
		)
		(fp_line
			(start 0.7874 0.4064)
			(end -0.7874 0.4064)
			(stroke
				(width 0.1524)
				(type default)
			)
			(layer "F.SilkS")
		)
		(fp_line
			(start -0.7874 0.4064)
			(end -0.7874 -0.4064)
			(stroke
				(width 0.1524)
				(type default)
			)
			(layer "F.SilkS")
		)
		(fp_line
			(start -0.12065 -0.305054)
			(end -0.12065 -0.2794)
			(stroke
				(width 0.1)
				(type default)
			)
			(layer "F.Fab")
		)
		(fp_line
			(start -0.67945 -0.305054)
			(end -0.12065 -0.305054)
			(stroke
				(width 0.1)
				(type default)
			)
			(layer "F.Fab")
		)
		(fp_line
			(start 0.67945 -0.3048)
			(end 0.67945 0.3048)
			(stroke
				(width 0.1)
				(type default)
			)
			(layer "F.Fab")
		)
		(fp_line
			(start 0.12065 -0.3048)
			(end 0.67945 -0.3048)
			(stroke
				(width 0.1)
				(type default)
			)
			(layer "F.Fab")
		)
		(fp_line
			(start 0.12065 -0.2794)
			(end 0.12065 -0.3048)
			(stroke
				(width 0.1)
				(type default)
			)
			(layer "F.Fab")
		)
		(fp_line
			(start -0.12065 -0.2794)
			(end 0.12065 -0.2794)
			(stroke
				(width 0.1)
				(type default)
			)
			(layer "F.Fab")
		)
		(fp_line
			(start 0.120396 0.2794)
			(end -0.12065 0.2794)
			(stroke
				(width 0.1)
				(type default)
			)
			(layer "F.Fab")
		)
		(fp_line
			(start -0.12065 0.2794)
			(end -0.12065 0.3048)
			(stroke
				(width 0.1)
				(type default)
			)
			(layer "F.Fab")
		)
		(fp_line
			(start 0.67945 0.3048)
			(end 0.120396 0.3048)
			(stroke
				(width 0.1)
				(type default)
			)
			(layer "F.Fab")
		)
		(fp_line
			(start 0.120396 0.3048)
			(end 0.120396 0.2794)
			(stroke
				(width 0.1)
				(type default)
			)
			(layer "F.Fab")
		)
		(fp_line
			(start -0.12065 0.3048)
			(end -0.67945 0.3048)
			(stroke
				(width 0.1)
				(type default)
			)
			(layer "F.Fab")
		)
		(fp_line
			(start -0.67945 0.3048)
			(end -0.67945 -0.305054)
			(stroke
				(width 0.1)
				(type default)
			)
			(layer "F.Fab")
		)
		(pad "1" smd circle
			(at -0.40005 0 90)
			(size 0 0)
			(layers "F.Cu" "F.Mask" "F.Paste")
			(net "GND")
		)
		(pad "2" smd circle
			(at 0.40005 0 90)
			(size 0 0)
			(layers "F.Cu" "F.Mask" "F.Paste")
			(net "USB_HUB2_TI_NC_MRP_ATEST")
		)
	)
)
